(kicad_pcb
	(version 20260206)
	(generator "pcbnew")
	(generator_version "10.0")
	(general
		(thickness 1.6)
		(legacy_teardrops no)
	)
	(paper "A4")
	(title_block
		(title "01162023_DA0F0TEBIF0_F0T_Expander_BD_F_brd_V02_OCP.brd")
		(comment 1 "Grand Teton / footprints 6457-6462 of 9728")
	)
	(layers
		(0 "F.Cu" signal "TOP")
		(4 "In1.Cu" signal "GND")
		(6 "In2.Cu" signal "VCC")
		(8 "In3.Cu" signal "VCC1")
		(10 "In4.Cu" signal "GND1")
		(12 "In5.Cu" signal "IN1")
		(14 "In6.Cu" signal "GND2")
		(16 "In7.Cu" signal "IN2")
		(18 "In8.Cu" signal "GND3")
		(20 "In9.Cu" signal "IN3")
		(22 "In10.Cu" signal "GND4")
		(24 "In11.Cu" signal "IN4")
		(26 "In12.Cu" signal "GND5")
		(28 "In13.Cu" signal "IN5")
		(30 "In14.Cu" signal "GND6")
		(32 "In15.Cu" signal "IN6")
		(34 "In16.Cu" signal "GND7")
		(2 "B.Cu" signal "BOTTOM")
		(9 "F.Adhes" user "F.Adhesive")
		(11 "B.Adhes" user "B.Adhesive")
		(13 "F.Paste" user "Package Geometry/Pastemask Top")
		(15 "B.Paste" user "Package Geometry/Pastemask Bottom")
		(5 "F.SilkS" user "Ref Des/Silkscreen Top")
		(7 "B.SilkS" user "Ref Des/Silkscreen Bottom")
		(1 "F.Mask" user "Board Geometry/Soldermask Top")
		(3 "B.Mask" user "Board Geometry/Soldermask Bottom")
		(17 "Dwgs.User" user "User.Drawings")
		(19 "Cmts.User" user "User.Comments")
		(21 "Eco1.User" user "User.Eco1")
		(23 "Eco2.User" user "User.Eco2")
		(25 "Edge.Cuts" user "Board Geometry/Outline")
		(27 "Margin" user)
		(31 "F.CrtYd" user "Package Geometry/Place Bound Top")
		(29 "B.CrtYd" user "Package Geometry/Place Bound Bottom")
		(35 "F.Fab" user "Ref Des/Assembly Top")
		(33 "B.Fab" user "Ref Des/Assembly Bottom")
	)
	(footprint ""
		(layer "F.Cu")
		(at 399.723864 -167.742108)
		(property "Reference" "C619"
			(at 0 0 0)
			(layer "F.SilkS")
			(hide yes)
			(effects
				(font
					(size 1.27 1.27)
				)
			)
		)
		(property "Value" ""
			(at 0 0 0)
			(layer "F.Fab")
			(effects
				(font
					(size 1.27 1.27)
				)
			)
		)
		(duplicate_pad_numbers_are_jumpers no)
		(fp_line
			(start -0.7874 -0.4064)
			(end 0.7874 -0.4064)
			(stroke
				(width 0.1524)
				(type default)
			)
			(layer "F.SilkS")
		)
		(fp_line
			(start -0.7874 0.4064)
			(end -0.7874 -0.4064)
			(stroke
				(width 0.1524)
				(type default)
			)
			(layer "F.SilkS")
		)
		(fp_line
			(start 0.7874 -0.4064)
			(end 0.7874 0.4064)
			(stroke
				(width 0.1524)
				(type default)
			)
			(layer "F.SilkS")
		)
		(fp_line
			(start 0.7874 0.4064)
			(end -0.7874 0.4064)
			(stroke
				(width 0.1524)
				(type default)
			)
			(layer "F.SilkS")
		)
		(fp_line
			(start -0.67945 -0.305054)
			(end -0.12065 -0.305054)
			(stroke
				(width 0.1)
				(type default)
			)
			(layer "F.Fab")
		)
		(fp_line
			(start -0.67945 0.3048)
			(end -0.67945 -0.305054)
			(stroke
				(width 0.1)
				(type default)
			)
			(layer "F.Fab")
		)
		(fp_line
			(start -0.12065 -0.305054)
			(end -0.12065 -0.2794)
			(stroke
				(width 0.1)
				(type default)
			)
			(layer "F.Fab")
		)
		(fp_line
			(start -0.12065 -0.2794)
			(end 0.12065 -0.2794)
			(stroke
				(width 0.1)
				(type default)
			)
			(layer "F.Fab")
		)
		(fp_line
			(start -0.12065 0.2794)
			(end -0.12065 0.3048)
			(stroke
				(width 0.1)
				(type default)
			)
			(layer "F.Fab")
		)
		(fp_line
			(start -0.12065 0.3048)
			(end -0.67945 0.3048)
			(stroke
				(width 0.1)
				(type default)
			)
			(layer "F.Fab")
		)
		(fp_line
			(start 0.120396 0.2794)
			(end -0.12065 0.2794)
			(stroke
				(width 0.1)
				(type default)
			)
			(layer "F.Fab")
		)
		(fp_line
			(start 0.120396 0.3048)
			(end 0.120396 0.2794)
			(stroke
				(width 0.1)
				(type default)
			)
			(layer "F.Fab")
		)
		(fp_line
			(start 0.12065 -0.3048)
			(end 0.67945 -0.3048)
			(stroke
				(width 0.1)
				(type default)
			)
			(layer "F.Fab")
		)
		(fp_line
			(start 0.12065 -0.2794)
			(end 0.12065 -0.3048)
			(stroke
				(width 0.1)
				(type default)
			)
			(layer "F.Fab")
		)
		(fp_line
			(start 0.67945 -0.3048)
			(end 0.67945 0.3048)
			(stroke
				(width 0.1)
				(type default)
			)
			(layer "F.Fab")
		)
		(fp_line
			(start 0.67945 0.3048)
			(end 0.120396 0.3048)
			(stroke
				(width 0.1)
				(type default)
			)
			(layer "F.Fab")
		)
		(pad "1" smd circle
			(at -0.40005 0)
			(size 0 0)
			(layers "F.Cu" "F.Mask" "F.Paste")
			(net "P3V3_AUX")
		)
		(pad "2" smd circle
			(at 0.40005 0)
			(size 0 0)
			(layers "F.Cu" "F.Mask" "F.Paste")
			(net "GND")
		)
	)
	(footprint ""
		(layer "F.Cu")
		(at 168.367964 -53.051456)
		(property "Reference" "R4461"
			(at 0 0 0)
			(layer "F.SilkS")
			(hide yes)
			(effects
				(font
					(size 1.27 1.27)
				)
			)
		)
		(property "Value" ""
			(at 0 0 0)
			(layer "F.Fab")
			(effects
				(font
					(size 1.27 1.27)
				)
			)
		)
		(duplicate_pad_numbers_are_jumpers no)
		(fp_line
			(start -0.7874 -0.4064)
			(end 0.7874 -0.4064)
			(stroke
				(width 0.1524)
				(type default)
			)
			(layer "F.SilkS")
		)
		(fp_line
			(start -0.7874 0.4064)
			(end -0.7874 -0.4064)
			(stroke
				(width 0.1524)
				(type default)
			)
			(layer "F.SilkS")
		)
		(fp_line
			(start 0.7874 -0.4064)
			(end 0.7874 0.4064)
			(stroke
				(width 0.1524)
				(type default)
			)
			(layer "F.SilkS")
		)
		(fp_line
			(start 0.7874 0.4064)
			(end -0.7874 0.4064)
			(stroke
				(width 0.1524)
				(type default)
			)
			(layer "F.SilkS")
		)
		(fp_line
			(start -0.67945 -0.305054)
			(end -0.12065 -0.305054)
			(stroke
				(width 0.1)
				(type default)
			)
			(layer "F.Fab")
		)
		(fp_line
			(start -0.67945 0.3048)
			(end -0.67945 -0.305054)
			(stroke
				(width 0.1)
				(type default)
			)
			(layer "F.Fab")
		)
		(fp_line
			(start -0.12065 -0.305054)
			(end -0.12065 -0.2794)
			(stroke
				(width 0.1)
				(type default)
			)
			(layer "F.Fab")
		)
		(fp_line
			(start -0.12065 -0.2794)
			(end 0.12065 -0.2794)
			(stroke
				(width 0.1)
				(type default)
			)
			(layer "F.Fab")
		)
		(fp_line
			(start -0.12065 0.2794)
			(end -0.12065 0.3048)
			(stroke
				(width 0.1)
				(type default)
			)
			(layer "F.Fab")
		)
		(fp_line
			(start -0.12065 0.3048)
			(end -0.67945 0.3048)
			(stroke
				(width 0.1)
				(type default)
			)
			(layer "F.Fab")
		)
		(fp_line
			(start 0.120396 0.2794)
			(end -0.12065 0.2794)
			(stroke
				(width 0.1)
				(type default)
			)
			(layer "F.Fab")
		)
		(fp_line
			(start 0.120396 0.3048)
			(end 0.120396 0.2794)
			(stroke
				(width 0.1)
				(type default)
			)
			(layer "F.Fab")
		)
		(fp_line
			(start 0.12065 -0.3048)
			(end 0.67945 -0.3048)
			(stroke
				(width 0.1)
				(type default)
			)
			(layer "F.Fab")
		)
		(fp_line
			(start 0.12065 -0.2794)
			(end 0.12065 -0.3048)
			(stroke
				(width 0.1)
				(type default)
			)
			(layer "F.Fab")
		)
		(fp_line
			(start 0.67945 -0.3048)
			(end 0.67945 0.3048)
			(stroke
				(width 0.1)
				(type default)
			)
			(layer "F.Fab")
		)
		(fp_line
			(start 0.67945 0.3048)
			(end 0.120396 0.3048)
			(stroke
				(width 0.1)
				(type default)
			)
			(layer "F.Fab")
		)
		(pad "1" smd circle
			(at -0.40005 0)
			(size 0 0)
			(layers "F.Cu" "F.Mask" "F.Paste")
			(net "PWRGD_P12V_SSD5")
		)
		(pad "2" smd circle
			(at 0.40005 0)
			(size 0 0)
			(layers "F.Cu" "F.Mask" "F.Paste")
			(net "PWRGD_P12V_SSD5_R")
		)
	)
	(footprint ""
		(layer "F.Cu")
		(at 213.17966 -181.608476 -90)
		(property "Reference" "R5299"
			(at 0 0 270)
			(layer "F.SilkS")
			(hide yes)
			(effects
				(font
					(size 1.27 1.27)
				)
			)
		)
		(property "Value" ""
			(at 0 0 270)
			(layer "F.Fab")
			(effects
				(font
					(size 1.27 1.27)
				)
			)
		)
		(duplicate_pad_numbers_are_jumpers no)
		(fp_line
			(start -0.7874 0.4064)
			(end -0.7874 -0.4064)
			(stroke
				(width 0.1524)
				(type default)
			)
			(layer "F.SilkS")
		)
		(fp_line
			(start 0.7874 0.4064)
			(end -0.7874 0.4064)
			(stroke
				(width 0.1524)
				(type default)
			)
			(layer "F.SilkS")
		)
		(fp_line
			(start -0.7874 -0.4064)
			(end 0.7874 -0.4064)
			(stroke
				(width 0.1524)
				(type default)
			)
			(layer "F.SilkS")
		)
		(fp_line
			(start 0.7874 -0.4064)
			(end 0.7874 0.4064)
			(stroke
				(width 0.1524)
				(type default)
			)
			(layer "F.SilkS")
		)
		(fp_line
			(start -0.67945 0.3048)
			(end -0.67945 -0.305054)
			(stroke
				(width 0.1)
				(type default)
			)
			(layer "F.Fab")
		)
		(fp_line
			(start -0.12065 0.3048)
			(end -0.67945 0.3048)
			(stroke
				(width 0.1)
				(type default)
			)
			(layer "F.Fab")
		)
		(fp_line
			(start 0.120396 0.3048)
			(end 0.120396 0.2794)
			(stroke
				(width 0.1)
				(type default)
			)
			(layer "F.Fab")
		)
		(fp_line
			(start 0.67945 0.3048)
			(end 0.120396 0.3048)
			(stroke
				(width 0.1)
				(type default)
			)
			(layer "F.Fab")
		)
		(fp_line
			(start -0.12065 0.2794)
			(end -0.12065 0.3048)
			(stroke
				(width 0.1)
				(type default)
			)
			(layer "F.Fab")
		)
		(fp_line
			(start 0.120396 0.2794)
			(end -0.12065 0.2794)
			(stroke
				(width 0.1)
				(type default)
			)
			(layer "F.Fab")
		)
		(fp_line
			(start -0.12065 -0.2794)
			(end 0.12065 -0.2794)
			(stroke
				(width 0.1)
				(type default)
			)
			(layer "F.Fab")
		)
		(fp_line
			(start 0.12065 -0.2794)
			(end 0.12065 -0.3048)
			(stroke
				(width 0.1)
				(type default)
			)
			(layer "F.Fab")
		)
		(fp_line
			(start 0.12065 -0.3048)
			(end 0.67945 -0.3048)
			(stroke
				(width 0.1)
				(type default)
			)
			(layer "F.Fab")
		)
		(fp_line
			(start 0.67945 -0.3048)
			(end 0.67945 0.3048)
			(stroke
				(width 0.1)
				(type default)
			)
			(layer "F.Fab")
		)
		(fp_line
			(start -0.67945 -0.305054)
			(end -0.12065 -0.305054)
			(stroke
				(width 0.1)
				(type default)
			)
			(layer "F.Fab")
		)
		(fp_line
			(start -0.12065 -0.305054)
			(end -0.12065 -0.2794)
			(stroke
				(width 0.1)
				(type default)
			)
			(layer "F.Fab")
		)
		(pad "1" smd circle
			(at -0.40005 0 270)
			(size 0 0)
			(layers "F.Cu" "F.Mask" "F.Paste")
			(net "SEL_FLASH_PEX2_BUF")
		)
		(pad "2" smd circle
			(at 0.40005 0 270)
			(size 0 0)
			(layers "F.Cu" "F.Mask" "F.Paste")
			(net "SEL_FLASH_PEX2_BUF_R")
		)
	)
	(footprint ""
		(layer "F.Cu")
		(at 238.124746 -112.888268 180)
		(property "Reference" "C842"
			(at 0 0 180)
			(layer "F.SilkS")
			(hide yes)
			(effects
				(font
					(size 1.27 1.27)
				)
			)
		)
		(property "Value" ""
			(at 0 0 180)
			(layer "F.Fab")
			(effects
				(font
					(size 1.27 1.27)
				)
			)
		)
		(duplicate_pad_numbers_are_jumpers no)
		(fp_line
			(start 0.7874 0.4064)
			(end -0.7874 0.4064)
			(stroke
				(width 0.1524)
				(type default)
			)
			(layer "F.SilkS")
		)
		(fp_line
			(start 0.7874 -0.4064)
			(end 0.7874 0.4064)
			(stroke
				(width 0.1524)
				(type default)
			)
			(layer "F.SilkS")
		)
		(fp_line
			(start -0.7874 0.4064)
			(end -0.7874 -0.4064)
			(stroke
				(width 0.1524)
				(type default)
			)
			(layer "F.SilkS")
		)
		(fp_line
			(start -0.7874 -0.4064)
			(end 0.7874 -0.4064)
			(stroke
				(width 0.1524)
				(type default)
			)
			(layer "F.SilkS")
		)
		(fp_line
			(start 0.67945 0.3048)
			(end 0.120396 0.3048)
			(stroke
				(width 0.1)
				(type default)
			)
			(layer "F.Fab")
		)
		(fp_line
			(start 0.67945 -0.3048)
			(end 0.67945 0.3048)
			(stroke
				(width 0.1)
				(type default)
			)
			(layer "F.Fab")
		)
		(fp_line
			(start 0.12065 -0.2794)
			(end 0.12065 -0.3048)
			(stroke
				(width 0.1)
				(type default)
			)
			(layer "F.Fab")
		)
		(fp_line
			(start 0.12065 -0.3048)
			(end 0.67945 -0.3048)
			(stroke
				(width 0.1)
				(type default)
			)
			(layer "F.Fab")
		)
		(fp_line
			(start 0.120396 0.3048)
			(end 0.120396 0.2794)
			(stroke
				(width 0.1)
				(type default)
			)
			(layer "F.Fab")
		)
		(fp_line
			(start 0.120396 0.2794)
			(end -0.12065 0.2794)
			(stroke
				(width 0.1)
				(type default)
			)
			(layer "F.Fab")
		)
		(fp_line
			(start -0.12065 0.3048)
			(end -0.67945 0.3048)
			(stroke
				(width 0.1)
				(type default)
			)
			(layer "F.Fab")
		)
		(fp_line
			(start -0.12065 0.2794)
			(end -0.12065 0.3048)
			(stroke
				(width 0.1)
				(type default)
			)
			(layer "F.Fab")
		)
		(fp_line
			(start -0.12065 -0.2794)
			(end 0.12065 -0.2794)
			(stroke
				(width 0.1)
				(type default)
			)
			(layer "F.Fab")
		)
		(fp_line
			(start -0.12065 -0.305054)
			(end -0.12065 -0.2794)
			(stroke
				(width 0.1)
				(type default)
			)
			(layer "F.Fab")
		)
		(fp_line
			(start -0.67945 0.3048)
			(end -0.67945 -0.305054)
			(stroke
				(width 0.1)
				(type default)
			)
			(layer "F.Fab")
		)
		(fp_line
			(start -0.67945 -0.305054)
			(end -0.12065 -0.305054)
			(stroke
				(width 0.1)
				(type default)
			)
			(layer "F.Fab")
		)
		(pad "1" smd circle
			(at -0.40005 0 180)
			(size 0 0)
			(layers "F.Cu" "F.Mask" "F.Paste")
			(net "GND")
		)
		(pad "2" smd circle
			(at 0.40005 0 180)
			(size 0 0)
			(layers "F.Cu" "F.Mask" "F.Paste")
			(net "P12V_NIC3_CO_EN")
		)
	)
	(footprint ""
		(layer "F.Cu")
		(at 411.428692 -207.945482)
		(property "Reference" "Q238"
			(at -3.236214 -1.629156 0)
			(unlocked yes)
			(layer "F.SilkS")
			(effects
				(font
					(size 0.7874 0.5842)
					(thickness 0.1524)
				)
			)
		)
		(property "Value" ""
			(at 0 0 0)
			(layer "F.Fab")
			(effects
				(font
					(size 1.27 1.27)
				)
			)
		)
		(duplicate_pad_numbers_are_jumpers no)
		(fp_line
			(start -1.376172 -1.199896)
			(end -0.508 -1.199896)
			(stroke
				(width 0.1524)
				(type default)
			)
			(layer "F.SilkS")
		)
		(fp_line
			(start -1.376172 1.199896)
			(end -1.376172 -1.199896)
			(stroke
				(width 0.1524)
				(type default)
			)
			(layer "F.SilkS")
		)
		(fp_line
			(start -0.508 -1.199896)
			(end 0 -0.762)
			(stroke
				(width 0.1524)
				(type default)
			)
			(layer "F.SilkS")
		)
		(fp_line
			(start 0 -0.762)
			(end 0.508 -1.199896)
			(stroke
				(width 0.1524)
				(type default)
			)
			(layer "F.SilkS")
		)
		(fp_line
			(start 0.508 -1.199896)
			(end 1.376172 -1.199896)
			(stroke
				(width 0.1524)
				(type default)
			)
			(layer "F.SilkS")
		)
		(fp_line
			(start 1.376172 -1.199896)
			(end 1.376172 1.199896)
			(stroke
				(width 0.1524)
				(type default)
			)
			(layer "F.SilkS")
		)
		(fp_line
			(start 1.376172 1.199896)
			(end -1.376172 1.199896)
			(stroke
				(width 0.1524)
				(type default)
			)
			(layer "F.SilkS")
		)
		(fp_poly
			(pts
				(xy -1.4605 -0.7493) (xy -2.2225 -1.1303) (xy -2.2225 -0.3683)
			)
			(stroke
				(width 0)
				(type default)
			)
			(fill yes)
			(layer "F.SilkS")
		)
		(fp_line
			(start -0.674878 -1.100074)
			(end 0.674878 -1.100074)
			(stroke
				(width 0.1)
				(type default)
			)
			(layer "F.Fab")
		)
		(fp_line
			(start -0.674878 1.100074)
			(end -0.674878 -1.100074)
			(stroke
				(width 0.1)
				(type default)
			)
			(layer "F.Fab")
		)
		(fp_line
			(start 0.674878 -1.100074)
			(end 0.674878 1.100074)
			(stroke
				(width 0.1)
				(type default)
			)
			(layer "F.Fab")
		)
		(fp_line
			(start 0.674878 1.100074)
			(end -0.674878 1.100074)
			(stroke
				(width 0.1)
				(type default)
			)
			(layer "F.Fab")
		)
		(fp_poly
			(pts
				(xy -1.4605 -0.7493) (xy -2.2225 -1.1303) (xy -2.2225 -0.3683)
			)
			(stroke
				(width 0)
				(type default)
			)
			(fill yes)
			(layer "F.Fab")
		)
		(pad "1" smd rect
			(at -0.899922 -0.750062 270)
			(size 0.6096 0.6096)
			(layers "F.Cu" "F.Mask" "F.Paste")
			(net "GND")
		)
		(pad "2" smd rect
			(at -0.899922 0 270)
			(size 0.4064 0.6096)
			(layers "F.Cu" "F.Mask" "F.Paste")
			(net "FPGA_PEX3_MODE_SEL1_R")
		)
		(pad "3" smd rect
			(at -0.899922 0.750062 270)
			(size 0.6096 0.6096)
			(layers "F.Cu" "F.Mask" "F.Paste")
			(net "FPGA_PEX3_MODE_SEL1_ISO")
		)
		(pad "4" smd rect
			(at 0.899922 0.750062 270)
			(size 0.6096 0.6096)
			(layers "F.Cu" "F.Mask" "F.Paste")
			(net "GND")
		)
		(pad "5" smd rect
			(at 0.899922 0 270)
			(size 0.4064 0.6096)
			(layers "F.Cu" "F.Mask" "F.Paste")
			(net "FPGA_PEX3_MODE_SEL1_D_N")
		)
		(pad "6" smd rect
			(at 0.899922 -0.750062 270)
			(size 0.6096 0.6096)
			(layers "F.Cu" "F.Mask" "F.Paste")
			(net "FPGA_PEX3_MODE_SEL1_D_N")
		)
	)
	(footprint ""
		(layer "F.Cu")
		(at 40.598344 -252.356874 -90)
		(property "Reference" "R1191"
			(at 0 0 270)
			(layer "F.SilkS")
			(hide yes)
			(effects
				(font
					(size 1.27 1.27)
				)
			)
		)
		(property "Value" ""
			(at 0 0 270)
			(layer "F.Fab")
			(effects
				(font
					(size 1.27 1.27)
				)
			)
		)
		(duplicate_pad_numbers_are_jumpers no)
		(fp_line
			(start -0.7874 0.4064)
			(end -0.7874 -0.4064)
			(stroke
				(width 0.1524)
				(type default)
			)
			(layer "F.SilkS")
		)
		(fp_line
			(start 0.7874 0.4064)
			(end -0.7874 0.4064)
			(stroke
				(width 0.1524)
				(type default)
			)
			(layer "F.SilkS")
		)
		(fp_line
			(start -0.7874 -0.4064)
			(end 0.7874 -0.4064)
			(stroke
				(width 0.1524)
				(type default)
			)
			(layer "F.SilkS")
		)
		(fp_line
			(start 0.7874 -0.4064)
			(end 0.7874 0.4064)
			(stroke
				(width 0.1524)
				(type default)
			)
			(layer "F.SilkS")
		)
		(fp_line
			(start -0.67945 0.3048)
			(end -0.67945 -0.305054)
			(stroke
				(width 0.1)
				(type default)
			)
			(layer "F.Fab")
		)
		(fp_line
			(start -0.12065 0.3048)
			(end -0.67945 0.3048)
			(stroke
				(width 0.1)
				(type default)
			)
			(layer "F.Fab")
		)
		(fp_line
			(start 0.120396 0.3048)
			(end 0.120396 0.2794)
			(stroke
				(width 0.1)
				(type default)
			)
			(layer "F.Fab")
		)
		(fp_line
			(start 0.67945 0.3048)
			(end 0.120396 0.3048)
			(stroke
				(width 0.1)
				(type default)
			)
			(layer "F.Fab")
		)
		(fp_line
			(start -0.12065 0.2794)
			(end -0.12065 0.3048)
			(stroke
				(width 0.1)
				(type default)
			)
			(layer "F.Fab")
		)
		(fp_line
			(start 0.120396 0.2794)
			(end -0.12065 0.2794)
			(stroke
				(width 0.1)
				(type default)
			)
			(layer "F.Fab")
		)
		(fp_line
			(start -0.12065 -0.2794)
			(end 0.12065 -0.2794)
			(stroke
				(width 0.1)
				(type default)
			)
			(layer "F.Fab")
		)
		(fp_line
			(start 0.12065 -0.2794)
			(end 0.12065 -0.3048)
			(stroke
				(width 0.1)
				(type default)
			)
			(layer "F.Fab")
		)
		(fp_line
			(start 0.12065 -0.3048)
			(end 0.67945 -0.3048)
			(stroke
				(width 0.1)
				(type default)
			)
			(layer "F.Fab")
		)
		(fp_line
			(start 0.67945 -0.3048)
			(end 0.67945 0.3048)
			(stroke
				(width 0.1)
				(type default)
			)
			(layer "F.Fab")
		)
		(fp_line
			(start -0.67945 -0.305054)
			(end -0.12065 -0.305054)
			(stroke
				(width 0.1)
				(type default)
			)
			(layer "F.Fab")
		)
		(fp_line
			(start -0.12065 -0.305054)
			(end -0.12065 -0.2794)
			(stroke
				(width 0.1)
				(type default)
			)
			(layer "F.Fab")
		)
		(pad "1" smd circle
			(at -0.40005 0 270)
			(size 0 0)
			(layers "F.Cu" "F.Mask" "F.Paste")
			(net "GND")
		)
		(pad "2" smd circle
			(at 0.40005 0 270)
			(size 0 0)
			(layers "F.Cu" "F.Mask" "F.Paste")
			(net "PEX0_MODE_SEL1")
		)
	)
)
